# BASEBOARD_FAB2 (Tioga Pass) — schematic netlist excerpt (pin names and nets, part order shuffled) for the footprints in the layout excerpt that follows; sources: Cadence DE-HDL packaged netlist, KiCad conversion of Wiwynn_Tioga_Pass_MB.brd

C6B2  CAP  10UF 4V 20% X6S  pkg 0603LF  page 232 : A = PVPP_DEF ; B = GND
R12W30  RES  0.0 5% EMPTY  pkg 0402  page 218 : A = TP_PVDDQ_DEF_MP2 ; B = PWRGD_PVDDQ_DEF
C7E10  CAP  1000PF 50V 10% X7R  pkg 0402LF  page 241 : A = PWRGD_P5V_STBY_R ; B = GND

(kicad_pcb
	(version 20260206)
	(generator "pcbnew")
	(generator_version "10.0")
	(general
		(thickness 1.6)
		(legacy_teardrops no)
	)
	(paper "A4")
	(title_block
		(title "Wiwynn_Tioga_Pass_MB.brd")
		(comment 1 "Tioga Pass / footprints 13-15 of 4770")
	)
	(layers
		(0 "F.Cu" signal "TOP")
		(4 "In1.Cu" signal "L2GND")
		(6 "In2.Cu" signal "L3")
		(8 "In3.Cu" signal "L4GND")
		(10 "In4.Cu" signal "L5")
		(12 "In5.Cu" signal "L6GND")
		(14 "In6.Cu" signal "L7VCC")
		(16 "In7.Cu" signal "L8VCC")
		(18 "In8.Cu" signal "L9GND")
		(20 "In9.Cu" signal "L10")
		(22 "In10.Cu" signal "L11GND")
		(24 "In11.Cu" signal "L12")
		(26 "In12.Cu" signal "L13GND")
		(2 "B.Cu" signal "BOTTOM")
		(9 "F.Adhes" user "F.Adhesive")
		(11 "B.Adhes" user "B.Adhesive")
		(13 "F.Paste" user "Package Geometry/Pastemask Top")
		(15 "B.Paste" user "Package Geometry/Pastemask Bottom")
		(5 "F.SilkS" user "Ref Des/Silkscreen Top")
		(7 "B.SilkS" user "Ref Des/Silkscreen Bottom")
		(1 "F.Mask" user "Board Geometry/Soldermask Top")
		(3 "B.Mask" user "Board Geometry/Soldermask Bottom")
		(17 "Dwgs.User" user "User.Drawings")
		(19 "Cmts.User" user "User.Comments")
		(21 "Eco1.User" user "User.Eco1")
		(23 "Eco2.User" user "User.Eco2")
		(25 "Edge.Cuts" user "Board Geometry/Outline")
		(27 "Margin" user)
		(31 "F.CrtYd" user "Package Geometry/Place Bound Top")
		(29 "B.CrtYd" user "Package Geometry/Place Bound Bottom")
		(35 "F.Fab" user "Ref Des/Assembly Top")
		(33 "B.Fab" user "Ref Des/Assembly Bottom")
	)
	(footprint ""
		(layer "F.Cu")
		(at 320.04 -130.3528 90)
		(property "Reference" "C6B2"
			(at 0 0 90)
			(layer "F.SilkS")
			(hide yes)
			(effects
				(font
					(size 1.27 1.27)
				)
			)
		)
		(property "Value" ""
			(at 0 0 90)
			(layer "F.Fab")
			(effects
				(font
					(size 1.27 1.27)
				)
			)
		)
		(duplicate_pad_numbers_are_jumpers no)
		(fp_poly
			(pts
				(xy -0.4953 -0.2032) (xy 0.4953 -0.2032) (xy 0.4953 1.6002) (xy -0.4953 1.6002)
			)
			(stroke
				(width 0)
				(type default)
			)
			(fill no)
			(layer "F.CrtYd")
		)
		(fp_line
			(start 0.4953 -0.2032)
			(end 0.4953 1.6002)
			(stroke
				(width 0.1)
				(type default)
			)
			(layer "F.Fab")
		)
		(fp_line
			(start -0.4953 -0.2032)
			(end 0.4953 -0.2032)
			(stroke
				(width 0.1)
				(type default)
			)
			(layer "F.Fab")
		)
		(fp_line
			(start 0.4953 1.6002)
			(end -0.4953 1.6002)
			(stroke
				(width 0.1)
				(type default)
			)
			(layer "F.Fab")
		)
		(fp_line
			(start -0.4953 1.6002)
			(end -0.4953 -0.2032)
			(stroke
				(width 0.1)
				(type default)
			)
			(layer "F.Fab")
		)
		(pad "1" smd rect
			(at 0 0 90)
			(size 0.762 0.889)
			(layers "F.Cu" "F.Mask" "F.Paste")
			(net "PVPP_DEF")
		)
		(pad "2" smd rect
			(at 0 1.397 90)
			(size 0.762 0.889)
			(layers "F.Cu" "F.Mask" "F.Paste")
			(net "GND")
		)
		(zone
			(layer "F.Cu")
			(hatch none 0.5)
			(connect_pads
				(clearance 0)
			)
			(min_thickness 0.25)
			(keepout
				(tracks not_allowed)
				(vias allowed)
				(pads allowed)
				(copperpour not_allowed)
				(footprints allowed)
			)
			(placement
				(enabled no)
				(sheetname "")
			)
			(fill
				(thermal_gap 0.5)
				(thermal_bridge_width 0.5)
				(island_removal_mode 0)
			)
			(polygon
				(pts
					(xy 320.4845 -129.9718) (xy 320.4845 -130.7338) (xy 320.9925 -130.7338) (xy 320.9925 -129.9718)
				)
			)
		)
	)
	(footprint ""
		(layer "F.Cu")
		(at 363.855 -140.081 90)
		(property "Reference" "R12W30"
			(at -0.8382 -0.67818 90)
			(unlocked yes)
			(layer "F.SilkS")
			(effects
				(font
					(size 0.4064 0.254)
					(thickness 0.1524)
				)
				(justify left)
			)
		)
		(property "Value" ""
			(at 0 0 90)
			(layer "F.Fab")
			(effects
				(font
					(size 1.27 1.27)
				)
			)
		)
		(duplicate_pad_numbers_are_jumpers no)
		(fp_poly
			(pts
				(xy -0.2794 -0.1016) (xy 0.2794 -0.1016) (xy 0.2794 0.9906) (xy -0.2794 0.9906)
			)
			(stroke
				(width 0)
				(type default)
			)
			(fill no)
			(layer "F.CrtYd")
		)
		(fp_line
			(start 0.2794 -0.1016)
			(end -0.2794 -0.1016)
			(stroke
				(width 0.1)
				(type default)
			)
			(layer "F.Fab")
		)
		(fp_line
			(start -0.2794 -0.1016)
			(end -0.2794 0.9906)
			(stroke
				(width 0.1)
				(type default)
			)
			(layer "F.Fab")
		)
		(fp_line
			(start 0.2794 0.9906)
			(end 0.2794 -0.1016)
			(stroke
				(width 0.1)
				(type default)
			)
			(layer "F.Fab")
		)
		(fp_line
			(start -0.2794 0.9906)
			(end 0.2794 0.9906)
			(stroke
				(width 0.1)
				(type default)
			)
			(layer "F.Fab")
		)
		(pad "1" smd rect
			(at 0 0 90)
			(size 0.508 0.508)
			(layers "F.Cu" "F.Mask" "F.Paste")
			(net "TP_PVDDQ_DEF_MP2")
		)
		(pad "2" smd rect
			(at 0 0.889 90)
			(size 0.508 0.508)
			(layers "F.Cu" "F.Mask" "F.Paste")
			(net "PWRGD_PVDDQ_DEF")
		)
		(zone
			(layer "F.Cu")
			(hatch none 0.5)
			(connect_pads
				(clearance 0)
			)
			(min_thickness 0.25)
			(keepout
				(tracks allowed)
				(vias not_allowed)
				(pads allowed)
				(copperpour not_allowed)
				(footprints allowed)
			)
			(placement
				(enabled no)
				(sheetname "")
			)
			(fill
				(thermal_gap 0.5)
				(thermal_bridge_width 0.5)
				(island_removal_mode 0)
			)
			(polygon
				(pts
					(xy 364.109 -139.827) (xy 364.109 -140.335) (xy 364.49 -140.335) (xy 364.49 -139.827)
				)
			)
		)
		(zone
			(layer "F.Cu")
			(hatch none 0.5)
			(connect_pads
				(clearance 0)
			)
			(min_thickness 0.25)
			(keepout
				(tracks not_allowed)
				(vias allowed)
				(pads allowed)
				(copperpour not_allowed)
				(footprints allowed)
			)
			(placement
				(enabled no)
				(sheetname "")
			)
			(fill
				(thermal_gap 0.5)
				(thermal_bridge_width 0.5)
				(island_removal_mode 0)
			)
			(polygon
				(pts
					(xy 364.49 -139.827) (xy 364.49 -140.335) (xy 364.109 -140.335) (xy 364.109 -139.827)
				)
			)
		)
	)
	(footprint ""
		(layer "F.Cu")
		(at 392.303 -71.0565 180)
		(property "Reference" "C7E10"
			(at 0 0 180)
			(layer "F.SilkS")
			(hide yes)
			(effects
				(font
					(size 1.27 1.27)
				)
			)
		)
		(property "Value" ""
			(at 0 0 180)
			(layer "F.Fab")
			(effects
				(font
					(size 1.27 1.27)
				)
			)
		)
		(duplicate_pad_numbers_are_jumpers no)
		(fp_poly
			(pts
				(xy 0.3048 -0.1016) (xy 0.3048 0.9906) (xy -0.3048 0.9906) (xy -0.3048 -0.1016)
			)
			(stroke
				(width 0)
				(type default)
			)
			(fill no)
			(layer "F.CrtYd")
		)
		(fp_line
			(start 0.3048 0.9906)
			(end 0.3048 -0.1016)
			(stroke
				(width 0.1)
				(type default)
			)
			(layer "F.Fab")
		)
		(fp_line
			(start 0.3048 -0.1016)
			(end -0.3048 -0.1016)
			(stroke
				(width 0.1)
				(type default)
			)
			(layer "F.Fab")
		)
		(fp_line
			(start -0.3048 0.9906)
			(end 0.3048 0.9906)
			(stroke
				(width 0.1)
				(type default)
			)
			(layer "F.Fab")
		)
		(fp_line
			(start -0.3048 -0.1016)
			(end -0.3048 0.9906)
			(stroke
				(width 0.1)
				(type default)
			)
			(layer "F.Fab")
		)
		(pad "1" smd rect
			(at 0 0 180)
			(size 0.508 0.508)
			(layers "F.Cu" "F.Mask" "F.Paste")
			(net "PWRGD_P5V_STBY_R")
		)
		(pad "2" smd rect
			(at 0 0.889 180)
			(size 0.508 0.508)
			(layers "F.Cu" "F.Mask" "F.Paste")
			(net "GND")
		)
		(zone
			(layer "F.Cu")
			(hatch none 0.5)
			(connect_pads
				(clearance 0)
			)
			(min_thickness 0.25)
			(keepout
				(tracks not_allowed)
				(vias allowed)
				(pads allowed)
				(copperpour not_allowed)
				(footprints allowed)
			)
			(placement
				(enabled no)
				(sheetname "")
			)
			(fill
				(thermal_gap 0.5)
				(thermal_bridge_width 0.5)
				(island_removal_mode 0)
			)
			(polygon
				(pts
					(xy 392.557 -71.6915) (xy 392.049 -71.6915) (xy 392.049 -71.3105) (xy 392.557 -71.3105)
				)
			)
		)
		(zone
			(layer "F.Cu")
			(hatch none 0.5)
			(connect_pads
				(clearance 0)
			)
			(min_thickness 0.25)
			(keepout
				(tracks allowed)
				(vias not_allowed)
				(pads allowed)
				(copperpour not_allowed)
				(footprints allowed)
			)
			(placement
				(enabled no)
				(sheetname "")
			)
			(fill
				(thermal_gap 0.5)
				(thermal_bridge_width 0.5)
				(island_removal_mode 0)
			)
			(polygon
				(pts
					(xy 392.557 -71.3105) (xy 392.049 -71.3105) (xy 392.049 -71.6915) (xy 392.557 -71.6915)
				)
			)
		)
	)
)
